# GPS_MODULE_NEO-M9N_BOM_smb-ver.xlsx — 844-XXXXX-XX-RevX1 (bom)
| Designator | Fitted | Quantity | Manufacturer | Manufacturer Part Number 1 | Supplier 1 | Supplier Part Number 1 | Footprint | Description | Comment |
| C4 | Fitted | 1 | Yageo | CC0402JRNPO9BN470 | Digi-Key | 311-1021-1-ND | c0402 | 0402 47 pF 50 V ±5 % Tolerance NP0 SMT Multilayer Ceramic Capacitor | 47pF 50V 0402 |
| R1, R5, R7, R8 | Fitted | 4 | Yageo | RC0402JR-070RL | Digi-Key | 311-0.0JRCT-ND | r0402 | RES SMD 0 OHM JUMPER 1/16W 0402 | 0 ohm 0402 |
| R4 | Fitted | 1 | Yageo | SR0603FR-7T10RL | Digi-Key | YAG5824CT-ND | r0603 | Res Surge Chip Thick Film 0603 10 Ohm 1% 1/4W ±200ppm/°C Molded Paper T/R | 10 OHM 1/4W 0603 |
| R6, R9, R10 | Not Fitted | 0 | Yageo | RC0402JR-070RL | Digi-Key | 311-0.0JRCT-ND | r0402 | RES SMD 0 OHM JUMPER 1/16W 0402 | DNI 0 ohm 0402 |
| LED1, LED2 | Fitted | 2 | Vishay Lite-On | LTST-C190KGKT | Digi-Key | 160-1435-1-ND | led0603 | LED High-Power Uni-Color Green 574nm 2-Pin Chip LED T/R | Green |
| U1 | Fitted | 1 | u-blox | NEO-M9N-00B | Digi-Key | 672-NEO-M9N-00BCT-ND | IC_NEO-M9N | GNSS module, Flash, TCXO, SAW, LNA, LCC, 12x16 mm Professional Grade | NEO-M9N-00B |
| R2, R3 | Fitted | 2 | TE Connectivity | CRGP0402F10K | Digi-Key | A130367CT-ND | r0402 | Res Thick Film 0402 10K Ohm 1% 0.125W(1/8W) ±100ppm/°C Pad SMD T/R | 10K 1/8W 0402 |
| J1 | Fitted | 1 | Sullins | NRPN042MAMS-RC | Digi-Key | S6009-04-ND | CONN_NRPN042MAMS-RC | Dual Row 8 Position 2 mm Pitch Surface Mount Header | NRPN042MAMS-RC 2MM |
| C2 | Fitted | 1 | Samsung | CL05B104KP5NNNC | Digi-Key | 1276-1002-1-ND | c0402 | CL05 Series 0.1 uF 10 V ±10 % Tolerance X7R SMT Multilayer Ceramic Capacitor | 100nF 10V 0402 |
| C1 | Fitted | 1 | Murata | GRM155R70J105KA12J | Digi-Key | 490-13339-1-ND | c0402 | 0402 1 uF 6.3 V ±10% Tolerance X7R Multilayer Ceramic Capacitor | 1uF 6V3 0402 |
| C3, C5 | Fitted | 2 | Murata | GCM155R71H103KA55D | Digi-Key | 490-4762-1-ND | c0402 | CAP CER 10000PF 50V X7R 0402 | 10nF 50V 0402 |
| L1 | Fitted | 1 | Murata | LQG15HS27NJ02D | Digi-Key | 490-2628-1-ND | L0402 | Inductor RF Chip Multi-Layer 27nH 5% 100MHz 8Q-Factor Air 300mA 460mOhm DCR 0402 Paper T/R | 27nH 300mA 460mohm 0402 |
| Q1 | Fitted | 1 | Diodes | DMG2302UKQ-7 | Digi-Key | 31-DMG2302UKQ-7CT-ND | SOT23 | N-Channel 20 V 2.8A (Ta) 660mW (Ta) Surface Mount SOT-23-3 | DMG2302UKQ-7 |
| J2 | Fitted | 1 | Bel Cinch | 131-3711-301 | Digi-Key | J10507-ND | CONN_131-3711-301 | Rf Coaxial Board Mount Connector | SMB_131-3711-301 |
